(kicad_pcb
	(version 20260206)
	(generator "pcbnew")
	(generator_version "10.0")
	(general
		(thickness 1.6)
		(legacy_teardrops no)
	)
	(paper "A4")
	(title_block
		(title "4HDD Backplane_Layout.brd")
		(comment 1 "Tioga Pass / footprints 90-95 of 97")
	)
	(layers
		(0 "F.Cu" signal "TOP")
		(4 "In1.Cu" signal "L2GND")
		(6 "In2.Cu" signal "L3")
		(8 "In3.Cu" signal "L4")
		(10 "In4.Cu" signal "L5GND")
		(2 "B.Cu" signal "BOTTOM")
		(9 "F.Adhes" user "F.Adhesive")
		(11 "B.Adhes" user "B.Adhesive")
		(13 "F.Paste" user "Package Geometry/Pastemask Top")
		(15 "B.Paste" user "Package Geometry/Pastemask Bottom")
		(5 "F.SilkS" user "Ref Des/Silkscreen Top")
		(7 "B.SilkS" user "Ref Des/Silkscreen Bottom")
		(1 "F.Mask" user "Board Geometry/Soldermask Top")
		(3 "B.Mask" user "Board Geometry/Soldermask Bottom")
		(17 "Dwgs.User" user "User.Drawings")
		(19 "Cmts.User" user "User.Comments")
		(21 "Eco1.User" user "User.Eco1")
		(23 "Eco2.User" user "User.Eco2")
		(25 "Edge.Cuts" user "Board Geometry/Outline")
		(27 "Margin" user)
		(31 "F.CrtYd" user "Package Geometry/Place Bound Top")
		(29 "B.CrtYd" user "Package Geometry/Place Bound Bottom")
		(35 "F.Fab" user "Ref Des/Assembly Top")
		(33 "B.Fab" user "Ref Des/Assembly Bottom")
	)
	(footprint ""
		(layer "B.Cu")
		(at 81.417922 -12.933426 90)
		(property "Reference" "PC1"
			(at 0 0 90)
			(layer "B.SilkS")
			(hide yes)
			(effects
				(font
					(size 1.27 1.27)
				)
				(justify mirror)
			)
		)
		(property "Value" "SC1U6D3V2KX-GP"
			(at -1.1811 -2.7051 90)
			(unlocked yes)
			(layer "B.Fab")
			(hide yes)
			(effects
				(font
					(size 1.016 1.016)
					(thickness 0.1524)
				)
				(justify mirror)
			)
		)
		(property "Device Type" "C402H22"
			(at -1.1811 -4.2291 90)
			(unlocked yes)
			(layer "B.Fab")
			(hide yes)
			(effects
				(font
					(size 1.016 1.016)
					(thickness 0.1524)
				)
				(justify mirror)
			)
		)
		(duplicate_pad_numbers_are_jumpers no)
		(fp_rect
			(start 0.4318 0.9525)
			(end -0.4318 -0.9525)
			(stroke
				(width 0)
				(type default)
			)
			(fill no)
			(layer "B.CrtYd")
		)
		(fp_rect
			(start 0.4318 0.9525)
			(end -0.4318 -0.9525)
			(stroke
				(width 0)
				(type default)
			)
			(fill no)
			(layer "B.Fab")
		)
		(pad "1" smd custom
			(at 0 -0.4445 270)
			(size 0.1524 0.1524)
			(layers "B.Cu" "B.Mask" "B.Paste")
			(net "P3V3")
			(options
				(clearance outline)
				(anchor circle)
			)
			(primitives
				(gr_poly
					(pts
						(arc
							(start 0.3048 0.2032)
							(mid 0.275042 0.275042)
							(end 0.2032 0.3048)
						)
						(arc
							(start -0.2032 0.3048)
							(mid -0.275042 0.275042)
							(end -0.3048 0.2032)
						)
						(arc
							(start -0.3048 -0.2032)
							(mid -0.275042 -0.275042)
							(end -0.2032 -0.3048)
						)
						(arc
							(start 0.2032 -0.3048)
							(mid 0.275042 -0.275042)
							(end 0.3048 -0.2032)
						)
					)
					(width 0)
					(fill yes)
				)
			)
		)
		(pad "2" smd custom
			(at 0 0.4445 270)
			(size 0.1524 0.1524)
			(layers "B.Cu" "B.Mask" "B.Paste")
			(net "GND")
			(options
				(clearance outline)
				(anchor circle)
			)
			(primitives
				(gr_poly
					(pts
						(arc
							(start 0.3048 0.2032)
							(mid 0.275042 0.275042)
							(end 0.2032 0.3048)
						)
						(arc
							(start -0.2032 0.3048)
							(mid -0.275042 0.275042)
							(end -0.3048 0.2032)
						)
						(arc
							(start -0.3048 -0.2032)
							(mid -0.275042 -0.275042)
							(end -0.2032 -0.3048)
						)
						(arc
							(start 0.2032 -0.3048)
							(mid 0.275042 -0.275042)
							(end 0.3048 -0.2032)
						)
					)
					(width 0)
					(fill yes)
				)
			)
		)
	)
	(footprint ""
		(layer "B.Cu")
		(at 123.77928 -25.680416 90)
		(property "Reference" "TC1"
			(at 0 0 90)
			(layer "B.SilkS")
			(hide yes)
			(effects
				(font
					(size 1.27 1.27)
				)
				(justify mirror)
			)
		)
		(property "Value" "SC22U25V5MX-GP"
			(at 0.0762 -6.1214 90)
			(unlocked yes)
			(layer "B.Fab")
			(hide yes)
			(effects
				(font
					(size 1.016 1.016)
					(thickness 0.1524)
				)
				(justify mirror)
			)
		)
		(property "Device Type" "C805H58"
			(at 0.0762 -8.1534 90)
			(unlocked yes)
			(layer "B.Fab")
			(hide yes)
			(effects
				(font
					(size 1.016 1.016)
					(thickness 0.1524)
				)
				(justify mirror)
			)
		)
		(duplicate_pad_numbers_are_jumpers no)
		(fp_line
			(start -0.635 0)
			(end 0.635 0)
			(stroke
				(width 0.508)
				(type default)
			)
			(layer "B.SilkS")
		)
		(fp_rect
			(start 0.9652 1.778)
			(end -0.9652 -1.778)
			(stroke
				(width 0)
				(type default)
			)
			(fill no)
			(layer "B.CrtYd")
		)
		(fp_poly
			(pts
				(xy 0.9652 -1.778) (xy -0.9652 -1.778) (xy -0.9652 1.778) (xy 0.9652 1.778)
			)
			(stroke
				(width 0)
				(type default)
			)
			(fill no)
			(layer "B.Fab")
		)
		(pad "1" smd rect
			(at 0 -0.9652 270)
			(size 1.397 1.143)
			(layers "B.Cu" "B.Mask" "B.Paste")
			(net "P12V")
		)
		(pad "2" smd rect
			(at 0 0.9652 270)
			(size 1.397 1.143)
			(layers "B.Cu" "B.Mask" "B.Paste")
			(net "GND")
		)
	)
	(footprint ""
		(layer "B.Cu")
		(at 72.411082 -7.169912)
		(property "Reference" "R167"
			(at 0 0 0)
			(layer "B.SilkS")
			(hide yes)
			(effects
				(font
					(size 1.27 1.27)
				)
				(justify mirror)
			)
		)
		(property "Value" "4K7R2J-2-GP"
			(at -0.064008 -3.993896 0)
			(unlocked yes)
			(layer "B.Fab")
			(hide yes)
			(effects
				(font
					(size 1.016 1.016)
					(thickness 0.1524)
				)
				(justify mirror)
			)
		)
		(property "Device Type" "R402H16"
			(at -0.064008 -5.517896 0)
			(unlocked yes)
			(layer "B.Fab")
			(hide yes)
			(effects
				(font
					(size 1.016 1.016)
					(thickness 0.1524)
				)
				(justify mirror)
			)
		)
		(duplicate_pad_numbers_are_jumpers no)
		(fp_line
			(start -0.508 -0.9398)
			(end 0.508 -0.9398)
			(stroke
				(width 0.1524)
				(type default)
			)
			(layer "B.SilkS")
		)
		(fp_line
			(start 0.508 -0.9398)
			(end 0.508 0.9398)
			(stroke
				(width 0.1524)
				(type default)
			)
			(layer "B.SilkS")
		)
		(fp_rect
			(start 0.508 0.9398)
			(end -0.508 -0.9398)
			(stroke
				(width 0)
				(type default)
			)
			(fill no)
			(layer "B.CrtYd")
		)
		(fp_rect
			(start 0.508 0.9398)
			(end -0.508 -0.9398)
			(stroke
				(width 0)
				(type default)
			)
			(fill no)
			(layer "B.Fab")
		)
		(pad "1" smd custom
			(at 0 -0.4445 180)
			(size 0.1397 0.1397)
			(layers "B.Cu" "B.Mask" "B.Paste")
			(net "P12V")
			(options
				(clearance outline)
				(anchor circle)
			)
			(primitives
				(gr_poly
					(pts
						(arc
							(start -0.1778 0.2794)
							(mid -0.249642 0.249642)
							(end -0.2794 0.1778)
						)
						(arc
							(start -0.2794 -0.1778)
							(mid -0.249642 -0.249642)
							(end -0.1778 -0.2794)
						)
						(arc
							(start 0.1778 -0.2794)
							(mid 0.249642 -0.249642)
							(end 0.2794 -0.1778)
						)
						(arc
							(start 0.2794 0.1778)
							(mid 0.249642 0.249642)
							(end 0.1778 0.2794)
						)
					)
					(width 0)
					(fill yes)
				)
			)
		)
		(pad "2" smd custom
			(at 0 0.4445 180)
			(size 0.1397 0.1397)
			(layers "B.Cu" "B.Mask" "B.Paste")
			(net "PWR_EN_L_P5V")
			(options
				(clearance outline)
				(anchor circle)
			)
			(primitives
				(gr_poly
					(pts
						(arc
							(start -0.1778 0.2794)
							(mid -0.249642 0.249642)
							(end -0.2794 0.1778)
						)
						(arc
							(start -0.2794 -0.1778)
							(mid -0.249642 -0.249642)
							(end -0.1778 -0.2794)
						)
						(arc
							(start 0.1778 -0.2794)
							(mid 0.249642 -0.249642)
							(end 0.2794 -0.1778)
						)
						(arc
							(start 0.2794 0.1778)
							(mid 0.249642 0.249642)
							(end 0.1778 0.2794)
						)
					)
					(width 0)
					(fill yes)
				)
			)
		)
	)
	(footprint ""
		(layer "B.Cu")
		(at 74.9046 -41.8592 -90)
		(property "Reference" "C12"
			(at 0 0 90)
			(layer "B.SilkS")
			(hide yes)
			(effects
				(font
					(size 1.27 1.27)
				)
				(justify mirror)
			)
		)
		(property "Value" "SCD1U25V2KX-GP"
			(at -1.1811 -2.7051 270)
			(unlocked yes)
			(layer "B.Fab")
			(hide yes)
			(effects
				(font
					(size 1.016 1.016)
					(thickness 0.1524)
				)
				(justify mirror)
			)
		)
		(property "Device Type" "C402H22"
			(at -1.1811 -4.2291 270)
			(unlocked yes)
			(layer "B.Fab")
			(hide yes)
			(effects
				(font
					(size 1.016 1.016)
					(thickness 0.1524)
				)
				(justify mirror)
			)
		)
		(duplicate_pad_numbers_are_jumpers no)
		(fp_rect
			(start 0.4318 0.9525)
			(end -0.4318 -0.9525)
			(stroke
				(width 0)
				(type default)
			)
			(fill no)
			(layer "B.CrtYd")
		)
		(fp_rect
			(start 0.4318 0.9525)
			(end -0.4318 -0.9525)
			(stroke
				(width 0)
				(type default)
			)
			(fill no)
			(layer "B.Fab")
		)
		(pad "1" smd custom
			(at 0 -0.4445 90)
			(size 0.1524 0.1524)
			(layers "B.Cu" "B.Mask" "B.Paste")
			(net "P12V_SW_R")
			(options
				(clearance outline)
				(anchor circle)
			)
			(primitives
				(gr_poly
					(pts
						(arc
							(start 0.3048 0.2032)
							(mid 0.275042 0.275042)
							(end 0.2032 0.3048)
						)
						(arc
							(start -0.2032 0.3048)
							(mid -0.275042 0.275042)
							(end -0.3048 0.2032)
						)
						(arc
							(start -0.3048 -0.2032)
							(mid -0.275042 -0.275042)
							(end -0.2032 -0.3048)
						)
						(arc
							(start 0.2032 -0.3048)
							(mid 0.275042 -0.275042)
							(end 0.3048 -0.2032)
						)
					)
					(width 0)
					(fill yes)
				)
			)
		)
		(pad "2" smd custom
			(at 0 0.4445 90)
			(size 0.1524 0.1524)
			(layers "B.Cu" "B.Mask" "B.Paste")
			(net "GND")
			(options
				(clearance outline)
				(anchor circle)
			)
			(primitives
				(gr_poly
					(pts
						(arc
							(start 0.3048 0.2032)
							(mid 0.275042 0.275042)
							(end 0.2032 0.3048)
						)
						(arc
							(start -0.2032 0.3048)
							(mid -0.275042 0.275042)
							(end -0.3048 0.2032)
						)
						(arc
							(start -0.3048 -0.2032)
							(mid -0.275042 -0.275042)
							(end -0.2032 -0.3048)
						)
						(arc
							(start 0.2032 -0.3048)
							(mid 0.275042 -0.275042)
							(end 0.3048 -0.2032)
						)
					)
					(width 0)
					(fill yes)
				)
			)
		)
	)
	(footprint ""
		(layer "B.Cu")
		(at 81.084166 -44.880276 180)
		(property "Reference" "Q8"
			(at 0 0 0)
			(layer "B.SilkS")
			(hide yes)
			(effects
				(font
					(size 1.27 1.27)
				)
				(justify mirror)
			)
		)
		(property "Value" "2N7002K-1-GP"
			(at -0.127 -8.9662 180)
			(unlocked yes)
			(layer "B.Fab")
			(hide yes)
			(effects
				(font
					(size 1.016 1.016)
					(thickness 0.1524)
				)
				(justify mirror)
			)
		)
		(property "Device Type" "SOT23DGS2D4H44"
			(at -0.127 -10.4902 180)
			(unlocked yes)
			(layer "B.Fab")
			(hide yes)
			(effects
				(font
					(size 1.016 1.016)
					(thickness 0.1524)
				)
				(justify mirror)
			)
		)
		(duplicate_pad_numbers_are_jumpers no)
		(fp_line
			(start 1.651 1.778)
			(end -1.651 1.778)
			(stroke
				(width 0.1524)
				(type default)
			)
			(layer "B.SilkS")
		)
		(fp_line
			(start 1.651 -1.778)
			(end 1.651 1.778)
			(stroke
				(width 0.1524)
				(type default)
			)
			(layer "B.SilkS")
		)
		(fp_line
			(start -1.651 1.778)
			(end -1.651 -1.778)
			(stroke
				(width 0.1524)
				(type default)
			)
			(layer "B.SilkS")
		)
		(fp_line
			(start -1.651 -1.778)
			(end 1.651 -1.778)
			(stroke
				(width 0.1524)
				(type default)
			)
			(layer "B.SilkS")
		)
		(fp_poly
			(pts
				(xy 1.778 1.8796) (xy 1.778 -1.8796) (xy -1.778 -1.8796) (xy -1.778 1.8796)
			)
			(stroke
				(width 0)
				(type default)
			)
			(fill no)
			(layer "B.CrtYd")
		)
		(fp_poly
			(pts
				(xy 1.778 1.8796) (xy 1.778 -1.8796) (xy -1.778 -1.8796) (xy -1.778 1.8796)
			)
			(stroke
				(width 0)
				(type default)
			)
			(fill no)
			(layer "B.Fab")
		)
		(pad "D" smd custom
			(at 0 -0.9525)
			(size 0.1905 0.1905)
			(layers "B.Cu" "B.Mask" "B.Paste")
			(net "PWR_EN_R_P5V")
			(options
				(clearance outline)
				(anchor circle)
			)
			(primitives
				(gr_poly
					(pts
						(arc
							(start -0.1778 -0.5715)
							(mid -0.321484 -0.511984)
							(end -0.381 -0.3683)
						)
						(arc
							(start -0.381 0.3683)
							(mid -0.321484 0.511984)
							(end -0.1778 0.5715)
						)
						(arc
							(start 0.1778 0.5715)
							(mid 0.321484 0.511984)
							(end 0.381 0.3683)
						)
						(arc
							(start 0.381 -0.3683)
							(mid 0.321484 -0.511984)
							(end 0.1778 -0.5715)
						)
					)
					(width 0)
					(fill yes)
				)
			)
		)
		(pad "G" smd custom
			(at 0.98425 0.9525)
			(size 0.1905 0.1905)
			(layers "B.Cu" "B.Mask" "B.Paste")
			(net "PWR_EN_R_N")
			(options
				(clearance outline)
				(anchor circle)
			)
			(primitives
				(gr_poly
					(pts
						(arc
							(start -0.1778 -0.5715)
							(mid -0.321484 -0.511984)
							(end -0.381 -0.3683)
						)
						(arc
							(start -0.381 0.3683)
							(mid -0.321484 0.511984)
							(end -0.1778 0.5715)
						)
						(arc
							(start 0.1778 0.5715)
							(mid 0.321484 0.511984)
							(end 0.381 0.3683)
						)
						(arc
							(start 0.381 -0.3683)
							(mid 0.321484 -0.511984)
							(end 0.1778 -0.5715)
						)
					)
					(width 0)
					(fill yes)
				)
			)
		)
		(pad "S" smd custom
			(at -0.98425 0.9525)
			(size 0.1905 0.1905)
			(layers "B.Cu" "B.Mask" "B.Paste")
			(net "GND")
			(options
				(clearance outline)
				(anchor circle)
			)
			(primitives
				(gr_poly
					(pts
						(arc
							(start -0.1778 -0.5715)
							(mid -0.321484 -0.511984)
							(end -0.381 -0.3683)
						)
						(arc
							(start -0.381 0.3683)
							(mid -0.321484 0.511984)
							(end -0.1778 0.5715)
						)
						(arc
							(start 0.1778 0.5715)
							(mid 0.321484 0.511984)
							(end 0.381 0.3683)
						)
						(arc
							(start 0.381 -0.3683)
							(mid 0.321484 -0.511984)
							(end 0.1778 -0.5715)
						)
					)
					(width 0)
					(fill yes)
				)
			)
		)
	)
	(footprint ""
		(layer "B.Cu")
		(at 123.735592 -27.125676 90)
		(property "Reference" "C27"
			(at 0 0 90)
			(layer "B.SilkS")
			(hide yes)
			(effects
				(font
					(size 1.27 1.27)
				)
				(justify mirror)
			)
		)
		(property "Value" "SCD1U25V2KX-GP"
			(at -1.1811 -2.7051 90)
			(unlocked yes)
			(layer "B.Fab")
			(hide yes)
			(effects
				(font
					(size 1.016 1.016)
					(thickness 0.1524)
				)
				(justify mirror)
			)
		)
		(property "Device Type" "C402H22"
			(at -1.1811 -4.2291 90)
			(unlocked yes)
			(layer "B.Fab")
			(hide yes)
			(effects
				(font
					(size 1.016 1.016)
					(thickness 0.1524)
				)
				(justify mirror)
			)
		)
		(duplicate_pad_numbers_are_jumpers no)
		(fp_rect
			(start 0.4318 0.9525)
			(end -0.4318 -0.9525)
			(stroke
				(width 0)
				(type default)
			)
			(fill no)
			(layer "B.CrtYd")
		)
		(fp_rect
			(start 0.4318 0.9525)
			(end -0.4318 -0.9525)
			(stroke
				(width 0)
				(type default)
			)
			(fill no)
			(layer "B.Fab")
		)
		(pad "1" smd custom
			(at 0 -0.4445 270)
			(size 0.1524 0.1524)
			(layers "B.Cu" "B.Mask" "B.Paste")
			(net "P12V")
			(options
				(clearance outline)
				(anchor circle)
			)
			(primitives
				(gr_poly
					(pts
						(arc
							(start 0.3048 0.2032)
							(mid 0.275042 0.275042)
							(end 0.2032 0.3048)
						)
						(arc
							(start -0.2032 0.3048)
							(mid -0.275042 0.275042)
							(end -0.3048 0.2032)
						)
						(arc
							(start -0.3048 -0.2032)
							(mid -0.275042 -0.275042)
							(end -0.2032 -0.3048)
						)
						(arc
							(start 0.2032 -0.3048)
							(mid 0.275042 -0.275042)
							(end 0.3048 -0.2032)
						)
					)
					(width 0)
					(fill yes)
				)
			)
		)
		(pad "2" smd custom
			(at 0 0.4445 270)
			(size 0.1524 0.1524)
			(layers "B.Cu" "B.Mask" "B.Paste")
			(net "GND")
			(options
				(clearance outline)
				(anchor circle)
			)
			(primitives
				(gr_poly
					(pts
						(arc
							(start 0.3048 0.2032)
							(mid 0.275042 0.275042)
							(end 0.2032 0.3048)
						)
						(arc
							(start -0.2032 0.3048)
							(mid -0.275042 0.275042)
							(end -0.3048 0.2032)
						)
						(arc
							(start -0.3048 -0.2032)
							(mid -0.275042 -0.275042)
							(end -0.2032 -0.3048)
						)
						(arc
							(start 0.2032 -0.3048)
							(mid 0.275042 -0.275042)
							(end 0.3048 -0.2032)
						)
					)
					(width 0)
					(fill yes)
				)
			)
		)
	)
)
